# S9S_MB_2U (Grand Teton) — schematic netlist excerpt (pin names and nets, part order shuffled) for the footprints in the layout excerpt that follows; sources: Cadence DE-HDL packaged netlist, KiCad conversion of 03242023_DA0F0TMBIJ0_F0T_Motherboard_J_brd_V01_OCP.brd

J27  SCONN288_ADR50017P130CC  SCONN288_ADR50017-P130CC IO  pkg DDR288S_1-1VXB  page 108
  VIN_BULK0  = P12V_S3_AUX_CPU1_NVDIMM
  RFU0  = TP_CHF_CPU1_DIMM1_FRU_0
  VIN_MGMT  = P3V3_AUX
  HSCL  = I3C_SPD_DDREFGH_CPU1_LVC1_SCL_2
  HSDA  = I3C_SPD_DDREFGH_CPU1_LVC1_SDA
  VSS0  = GND
  DQ0_A  = M_F_CPU1_SA_DQ<0>
  VSS1  = GND
  DQ1_A  = M_F_CPU1_SA_DQ<1>
  VSS2  = GND
  DQS0_A_T  = M_F_CPU1_SA_DQS_DP<0>
  DQS0_A_C  = M_F_CPU1_SA_DQS_DN<0>
  VSS3  = GND
  DQ4_A  = M_F_CPU1_SA_DQ<4>
  VSS4  = GND
  DQ5_A  = M_F_CPU1_SA_DQ<5>
  VSS5  = GND
  DQ8_A  = M_F_CPU1_SA_DQ<8>
  VSS6  = GND
  DQ9_A  = M_F_CPU1_SA_DQ<9>
  VSS7  = GND
  DQS1_A_T  = M_F_CPU1_SA_DQS_DP<1>
  DQS1_A_C  = M_F_CPU1_SA_DQS_DN<1>
  VSS8  = GND
  DQ12_A  = M_F_CPU1_SA_DQ<12>
  VSS9  = GND
  DQ13_A  = M_F_CPU1_SA_DQ<13>
  VSS10  = GND
  DQ16_A  = M_F_CPU1_SA_DQ<16>
  VSS11  = GND
  DQ17_A  = M_F_CPU1_SA_DQ<17>
  VSS12  = GND
  DQS2_A_T  = M_F_CPU1_SA_DQS_DP<2>
  DQS2_A_C  = M_F_CPU1_SA_DQS_DN<2>
  VSS13  = GND
  DQ20_A  = M_F_CPU1_SA_DQ<20>
  VSS14  = GND
  DQ21_A  = M_F_CPU1_SA_DQ<21>
  VSS15  = GND
  DQ24_A  = M_F_CPU1_SA_DQ<24>
  VSS16  = GND
  DQ25_A  = M_F_CPU1_SA_DQ<25>
  VSS17  = GND
  DQS3_A_T  = M_F_CPU1_SA_DQS_DP<3>
  DQS3_A_C  = M_F_CPU1_SA_DQS_DN<3>
  VSS18  = GND
  DQ28_A  = M_F_CPU1_SA_DQ<28>
  VSS19  = GND
  DQ29_A  = M_F_CPU1_SA_DQ<29>
  VSS20  = GND
  CB0_A  = M_F_CPU1_SA_CB<0>
  VSS21  = GND
  CB1_A  = M_F_CPU1_SA_CB<1>
  VSS22  = GND
  DQS4_A_T  = M_F_CPU1_SA_DQS_DP<4>
  DQS4_A_C  = M_F_CPU1_SA_DQS_DN<4>
  VSS23  = GND
  CB4_A  = M_F_CPU1_SA_CB<4>
  VSS24  = GND
  CB5_A  = M_F_CPU1_SA_CB<5>
  VSS25  = GND
  ALERT_N  = M_F_CPU1_ALERT_N
  VSS26  = GND
  CS0_A_N  = M_F_CPU1_SA_CS_N<0>
  VSS27  = GND
  CA0_A  = M_F_CPU1_SA_CA<0>
  VSS28  = GND
  CA2_A  = M_F_CPU1_SA_CA<2>
  VSS29  = GND
  CA4_A  = M_F_CPU1_SA_CA<4>
  VSS30  = GND
  CA6_A  = M_F_CPU1_SA_CA<6>
  VSS31  = GND
  PAR_A  = M_F_CPU1_SA_PAR
  VSS32  = GND
  CA0_B  = M_F_CPU1_SB_CA<0>
  VSS33  = GND
  CA2_B  = M_F_CPU1_SB_CA<2>
  VSS34  = GND
  CA4_B  = M_F_CPU1_SB_CA<4>
  VSS35  = GND
  CA6_B  = M_F_CPU1_SB_CA<6>
  VSS36  = GND
  CS0_B_N  = M_F_CPU1_SB_CS_N<0>
  VSS37  = GND
  \lbd||rsp_a_n\  = M_F_CPU1_SA_RSP<0>
  \lbs||rsp_b_n\  = M_F_CPU1_SB_RSP<0>
  VSS38  = GND
  CB4_B  = M_F_CPU1_SB_CB<4>
  VSS39  = GND
  CB5_B  = M_F_CPU1_SB_CB<5>
  VSS40  = GND
  \dqs9_b_t||tdqs9_b_t||dbi4_b_n\  = M_F_CPU1_SB_DQS_DP<9>
  \dqs9_b_c||tdqs9_b_c\  = M_F_CPU1_SB_DQS_DN<9>
  VSS41  = GND
  CB0_B  = M_F_CPU1_SB_CB<0>
  VSS42  = GND
  CB1_B  = M_F_CPU1_SB_CB<1>
  VSS43  = GND
  DQ0_B  = M_F_CPU1_SB_DQ<0>
  VSS44  = GND
  DQ1_B  = M_F_CPU1_SB_DQ<1>
  VSS45  = GND
  DQS0_B_T  = M_F_CPU1_SB_DQS_DP<0>
  DQS0_B_C  = M_F_CPU1_SB_DQS_DN<0>
  VSS46  = GND
  DQ4_B  = M_F_CPU1_SB_DQ<4>
  VSS47  = GND
  DQ5_B  = M_F_CPU1_SB_DQ<5>
  VSS48  = GND
  DQ8_B  = M_F_CPU1_SB_DQ<8>
  VSS49  = GND
  DQ9_B  = M_F_CPU1_SB_DQ<9>
  VSS50  = GND
  DQS1_B_T  = M_F_CPU1_SB_DQS_DP<1>
  DQS1_B_C  = M_F_CPU1_SB_DQS_DN<1>
  VSS51  = GND
  DQ12_B  = M_F_CPU1_SB_DQ<12>
  VSS52  = GND
  DQ13_B  = M_F_CPU1_SB_DQ<13>
  VSS53  = GND
  DQ16_B  = M_F_CPU1_SB_DQ<16>
  VSS54  = GND
  DQ17_B  = M_F_CPU1_SB_DQ<17>
  VSS55  = GND
  DQS2_B_T  = M_F_CPU1_SB_DQS_DP<2>
  DQS2_B_C  = M_F_CPU1_SB_DQS_DN<2>
  VSS56  = GND
  DQ20_B  = M_F_CPU1_SB_DQ<20>
  VSS57  = GND
  DQ21_B  = M_F_CPU1_SB_DQ<21>
  VSS58  = GND
  DQ24_B  = M_F_CPU1_SB_DQ<24>
  VSS59  = GND
  DQ25_B  = M_F_CPU1_SB_DQ<25>
  VSS60  = GND
  DQS3_B_T  = M_F_CPU1_SB_DQS_DP<3>
  DQS3_B_C  = M_F_CPU1_SB_DQS_DN<3>
  VSS61  = GND
  DQ28_B  = M_F_CPU1_SB_DQ<28>
  VSS62  = GND
  DQ29_B  = M_F_CPU1_SB_DQ<29>
  VSS63  = GND
  RFU1  = TP_CHF_CPU1_DIMM1_FRU_1
  VIN_BULK1  = P12V_S3_AUX_CPU1_NVDIMM
  VIN_BULK2  = P12V_S3_AUX_CPU1_NVDIMM
  \pwr_good||fail_n\  = PWRGD_CHF_CPU1_DIMM1
  HSA  = PD_CHF_CPU1_DIMM1_SAA
  RFU2  = TP_CHF_CPU1_DIMM1_FRU_2
  RFU3  = TP_CHF_CPU1_DIMM1_FRU_3
  VSS64  = GND
  DQ2_A  = M_F_CPU1_SA_DQ<2>
  VSS65  = GND
  DQ3_A  = M_F_CPU1_SA_DQ<3>
  VSS66  = GND
  \dqs5_a_c||tdqs5_a_c||dqs5_a_t||tdqs5_a_t\  = M_F_CPU1_SA_DQS_DN<5>
  \dqs5_a_t||tdqs5_a_t\  = M_F_CPU1_SA_DQS_DP<5>
  VSS67  = GND
  DQ6_A  = M_F_CPU1_SA_DQ<6>
  VSS68  = GND
  DQ7_A  = M_F_CPU1_SA_DQ<7>
  VSS69  = GND
  DQ10_A  = M_F_CPU1_SA_DQ<10>
  VSS70  = GND
  DQ11_A  = M_F_CPU1_SA_DQ<11>
  VSS71  = GND
  \dqs6_a_c||tdqs6_a_c||dqs6_a_t||tdqs6_a_t\  = M_F_CPU1_SA_DQS_DN<6>
  \dqs6_a_t||tdqs6_a_t\  = M_F_CPU1_SA_DQS_DP<6>
  VSS72  = GND
  DQ14_A  = M_F_CPU1_SA_DQ<14>
  VSS73  = GND
  DQ15_A  = M_F_CPU1_SA_DQ<15>
  VSS74  = GND
  DQ18_A  = M_F_CPU1_SA_DQ<18>
  VSS75  = GND
  DQ19_A  = M_F_CPU1_SA_DQ<19>
  VSS76  = GND
  \dqs7_a_c||tdqs7_a_c\  = M_F_CPU1_SA_DQS_DN<7>
  \dqs7_a_t||tdqs7_a_t\  = M_F_CPU1_SA_DQS_DP<7>
  VSS77  = GND
  DQ22_A  = M_F_CPU1_SA_DQ<22>
  VSS78  = GND
  DQ23_A  = M_F_CPU1_SA_DQ<23>
  VSS79  = GND
  DQ26_A  = M_F_CPU1_SA_DQ<26>
  VSS80  = GND
  DQ27_A  = M_F_CPU1_SA_DQ<27>
  VSS81  = GND
  \dqs8_a_c||tdqs8_a_c\  = M_F_CPU1_SA_DQS_DN<8>
  \dqs8_a_t||tdqs8_a_t\  = M_F_CPU1_SA_DQS_DP<8>
  VSS82  = GND
  DQ30_A  = M_F_CPU1_SA_DQ<30>
  VSS83  = GND
  DQ31_A  = M_F_CPU1_SA_DQ<31>
  VSS84  = GND
  CB2_A  = M_F_CPU1_SA_CB<2>
  VSS85  = GND
  CB3_A  = M_F_CPU1_SA_CB<3>
  VSS86  = GND
  \dqs9_a_c||tdqs9_a_c\  = M_F_CPU1_SA_DQS_DN<9>
  \dqs9_a_t||tdqs9_a_t\  = M_F_CPU1_SA_DQS_DP<9>
  VSS87  = GND
  CB6_A  = M_F_CPU1_SA_CB<6>
  VSS88  = GND
  CB7_A  = M_F_CPU1_SA_CB<7>
  VSS89  = GND
  RESET_N  = RST_M_EF_CPU1_FPGA_N
  VSS90  = GND
  CS1_A_N  = M_F_CPU1_SA_CS_N<1>
  VSS91  = GND
  CA1_A  = M_F_CPU1_SA_CA<1>
  VSS92  = GND
  CA3_A  = M_F_CPU1_SA_CA<3>
  VSS93  = GND
  CA5_A  = M_F_CPU1_SA_CA<5>
  VSS94  = GND
  CK_T  = M_F_CPU1_CLK_DP<0>
  CK_C  = M_F_CPU1_CLK_DN<0>
  VSS95  = GND
  RFU4  = TP_CHF_CPU1_DIMM1_FRU_4
  CA1_B  = M_F_CPU1_SB_CA<1>
  VSS96  = GND
  CA3_B  = M_F_CPU1_SB_CA<3>
  VSS97  = GND
  CA5_B  = M_F_CPU1_SB_CA<5>
  VSS98  = GND
  PAR_B  = M_F_CPU1_SB_PAR
  VSS99  = GND
  CS1_B_N  = M_F_CPU1_SB_CS_N<1>
  VSS100  = GND
  RFU5  = TP_CHF_CPU1_DIMM1_FRU_5
  RFU6  = TP_CHF_CPU1_DIMM1_FRU_6
  VSS101  = GND
  CB6_B  = M_F_CPU1_SB_CB<6>
  VSS102  = GND
  CB7_B  = M_F_CPU1_SB_CB<7>
  VSS103  = GND
  DQS4_B_C  = M_F_CPU1_SB_DQS_DN<4>
  DQS4_B_T  = M_F_CPU1_SB_DQS_DP<4>
  VSS104  = GND
  CB2_B  = M_F_CPU1_SB_CB<2>
  VSS105  = GND
  CB3_B  = M_F_CPU1_SB_CB<3>
  VSS106  = GND
  DQ2_B  = M_F_CPU1_SB_DQ<2>
  VSS107  = GND
  DQ3_B  = M_F_CPU1_SB_DQ<3>
  VSS108  = GND
  \dqs5_b_c||tdqs5_b_c\  = M_F_CPU1_SB_DQS_DN<5>
  \dqs5_b_t||tdqs5_b_t\  = M_F_CPU1_SB_DQS_DP<5>
  VSS109  = GND
  DQ6_B  = M_F_CPU1_SB_DQ<6>
  VSS110  = GND
  DQ7_B  = M_F_CPU1_SB_DQ<7>
  VSS111  = GND
  DQ10_B  = M_F_CPU1_SB_DQ<10>
  VSS112  = GND
  DQ11_B  = M_F_CPU1_SB_DQ<11>
  VSS113  = GND
  \dqs6_b_c||tdqs6_b_c\  = M_F_CPU1_SB_DQS_DN<6>
  \dqs6_b_t||tdqs6_b_t\  = M_F_CPU1_SB_DQS_DP<6>
  VSS114  = GND
  DQ14_B  = M_F_CPU1_SB_DQ<14>
  VSS115  = GND
  DQ15_B  = M_F_CPU1_SB_DQ<15>
  VSS116  = GND
  DQ18_B  = M_F_CPU1_SB_DQ<18>
  VSS117  = GND
  DQ19_B  = M_F_CPU1_SB_DQ<19>
  VSS118  = GND
  \dqs7_b_c||tdqs7_b_c\  = M_F_CPU1_SB_DQS_DN<7>
  \dqs7_b_t||tdqs7_b_t\  = M_F_CPU1_SB_DQS_DP<7>
  VSS119  = GND
  DQ22_B  = M_F_CPU1_SB_DQ<22>
  VSS120  = GND
  DQ23_B  = M_F_CPU1_SB_DQ<23>
  VSS121  = GND
  DQ26_B  = M_F_CPU1_SB_DQ<26>
  VSS122  = GND
  DQ27_B  = M_F_CPU1_SB_DQ<27>
  VSS123  = GND
  \dqs8_b_c||tdqs8_b_c\  = M_F_CPU1_SB_DQS_DN<8>
  \dqs8_b_t||tdqs8_b_t\  = M_F_CPU1_SB_DQS_DP<8>
  VSS124  = GND
  DQ30_B  = M_F_CPU1_SB_DQ<30>
  VSS125  = GND
  DQ31_B  = M_F_CPU1_SB_DQ<31>
  VSS126  = GND
  G1  = GND
  G2  = GND
  G3  = GND

(kicad_pcb
	(version 20260206)
	(generator "pcbnew")
	(generator_version "10.0")
	(general
		(thickness 1.6)
		(legacy_teardrops no)
	)
	(paper "A4")
	(title_block
		(title "03242023_DA0F0TMBIJ0_F0T_Motherboard_J_brd_V01_OCP.brd")
		(comment 1 "Grand Teton / footprint 1301 of 6105 (J27), pads 183-228 of 291")
	)
	(layers
		(0 "F.Cu" signal "TOP")
		(4 "In1.Cu" signal "GND")
		(6 "In2.Cu" signal "IN1")
		(8 "In3.Cu" signal "GND1")
		(10 "In4.Cu" signal "IN2")
		(12 "In5.Cu" signal "GND2")
		(14 "In6.Cu" signal "IN3")
		(16 "In7.Cu" signal "GND3")
		(18 "In8.Cu" signal "VCC")
		(20 "In9.Cu" signal "VCC1")
		(22 "In10.Cu" signal "GND4")
		(24 "In11.Cu" signal "IN4")
		(26 "In12.Cu" signal "GND5")
		(28 "In13.Cu" signal "IN5")
		(30 "In14.Cu" signal "GND6")
		(32 "In15.Cu" signal "IN6")
		(34 "In16.Cu" signal "GND7")
		(2 "B.Cu" signal "BOTTOM")
		(9 "F.Adhes" user "F.Adhesive")
		(11 "B.Adhes" user "B.Adhesive")
		(13 "F.Paste" user "Package Geometry/Pastemask Top")
		(15 "B.Paste" user "Package Geometry/Pastemask Bottom")
		(5 "F.SilkS" user "Ref Des/Silkscreen Top")
		(7 "B.SilkS" user "Ref Des/Silkscreen Bottom")
		(1 "F.Mask" user "Board Geometry/Soldermask Top")
		(3 "B.Mask" user "Board Geometry/Soldermask Bottom")
		(17 "Dwgs.User" user "User.Drawings")
		(19 "Cmts.User" user "User.Comments")
		(21 "Eco1.User" user "User.Eco1")
		(23 "Eco2.User" user "User.Eco2")
		(25 "Edge.Cuts" user "Board Geometry/Outline")
		(27 "Margin" user)
		(31 "F.CrtYd" user "Package Geometry/Place Bound Top")
		(29 "B.CrtYd" user "Package Geometry/Place Bound Bottom")
		(35 "F.Fab" user "Ref Des/Assembly Top")
		(33 "B.Fab" user "Ref Des/Assembly Bottom")
	)
	(footprint ""
		(layer "F.Cu")
		(at 183.49468 -258.091686)
		(property "Reference" "J27"
			(at 2.19456 -81.755488 0)
			(unlocked yes)
			(layer "F.SilkS")
			(effects
				(font
					(size 0.7874 0.5842)
					(thickness 0.1524)
				)
				(justify left)
			)
		)
		(property "Value" ""
			(at 0 0 0)
			(layer "F.Fab")
			(effects
				(font
					(size 1.27 1.27)
				)
			)
		)
		(duplicate_pad_numbers_are_jumpers no)
		(pad "183" smd rect
			(at 2.050034 -31.025084 270)
			(size 0.519938 1.4986)
			(layers "F.Cu" "F.Mask" "F.Paste")
			(net "M_F_CPU1_SA_DQ<23>")
		)
		(pad "184" smd rect
			(at 2.050034 -30.174946 270)
			(size 0.519938 1.4986)
			(layers "F.Cu" "F.Mask" "F.Paste")
			(net "GND")
		)
		(pad "185" smd rect
			(at 2.050034 -29.325062 270)
			(size 0.519938 1.4986)
			(layers "F.Cu" "F.Mask" "F.Paste")
			(net "M_F_CPU1_SA_DQ<26>")
		)
		(pad "186" smd rect
			(at 2.050034 -28.474924 270)
			(size 0.519938 1.4986)
			(layers "F.Cu" "F.Mask" "F.Paste")
			(net "GND")
		)
		(pad "187" smd rect
			(at 2.050034 -27.62504 270)
			(size 0.519938 1.4986)
			(layers "F.Cu" "F.Mask" "F.Paste")
			(net "M_F_CPU1_SA_DQ<27>")
		)
		(pad "188" smd rect
			(at 2.050034 -26.774902 270)
			(size 0.519938 1.4986)
			(layers "F.Cu" "F.Mask" "F.Paste")
			(net "GND")
		)
		(pad "189" smd rect
			(at 2.050034 -25.925018 270)
			(size 0.519938 1.4986)
			(layers "F.Cu" "F.Mask" "F.Paste")
			(net "M_F_CPU1_SA_DQS_DN<8>")
		)
		(pad "190" smd rect
			(at 2.050034 -25.07488 270)
			(size 0.519938 1.4986)
			(layers "F.Cu" "F.Mask" "F.Paste")
			(net "M_F_CPU1_SA_DQS_DP<8>")
		)
		(pad "191" smd rect
			(at 2.050034 -24.224996 270)
			(size 0.519938 1.4986)
			(layers "F.Cu" "F.Mask" "F.Paste")
			(net "GND")
		)
		(pad "192" smd rect
			(at 2.050034 -23.375112 270)
			(size 0.519938 1.4986)
			(layers "F.Cu" "F.Mask" "F.Paste")
			(net "M_F_CPU1_SA_DQ<30>")
		)
		(pad "193" smd rect
			(at 2.050034 -22.524974 270)
			(size 0.519938 1.4986)
			(layers "F.Cu" "F.Mask" "F.Paste")
			(net "GND")
		)
		(pad "194" smd rect
			(at 2.050034 -21.67509 270)
			(size 0.519938 1.4986)
			(layers "F.Cu" "F.Mask" "F.Paste")
			(net "M_F_CPU1_SA_DQ<31>")
		)
		(pad "195" smd rect
			(at 2.050034 -20.824952 270)
			(size 0.519938 1.4986)
			(layers "F.Cu" "F.Mask" "F.Paste")
			(net "GND")
		)
		(pad "196" smd rect
			(at 2.050034 -19.975068 270)
			(size 0.519938 1.4986)
			(layers "F.Cu" "F.Mask" "F.Paste")
			(net "M_F_CPU1_SA_CB<2>")
		)
		(pad "197" smd rect
			(at 2.050034 -19.12493 270)
			(size 0.519938 1.4986)
			(layers "F.Cu" "F.Mask" "F.Paste")
			(net "GND")
		)
		(pad "198" smd rect
			(at 2.050034 -18.275046 270)
			(size 0.519938 1.4986)
			(layers "F.Cu" "F.Mask" "F.Paste")
			(net "M_F_CPU1_SA_CB<3>")
		)
		(pad "199" smd rect
			(at 2.050034 -17.424908 270)
			(size 0.519938 1.4986)
			(layers "F.Cu" "F.Mask" "F.Paste")
			(net "GND")
		)
		(pad "200" smd rect
			(at 2.050034 -16.575024 270)
			(size 0.519938 1.4986)
			(layers "F.Cu" "F.Mask" "F.Paste")
			(net "M_F_CPU1_SA_DQS_DN<9>")
		)
		(pad "201" smd rect
			(at 2.050034 -15.724886 270)
			(size 0.519938 1.4986)
			(layers "F.Cu" "F.Mask" "F.Paste")
			(net "M_F_CPU1_SA_DQS_DP<9>")
		)
		(pad "202" smd rect
			(at 2.050034 -14.875002 270)
			(size 0.519938 1.4986)
			(layers "F.Cu" "F.Mask" "F.Paste")
			(net "GND")
		)
		(pad "203" smd rect
			(at 2.050034 -14.025118 270)
			(size 0.519938 1.4986)
			(layers "F.Cu" "F.Mask" "F.Paste")
			(net "M_F_CPU1_SA_CB<6>")
		)
		(pad "204" smd rect
			(at 2.050034 -13.17498 270)
			(size 0.519938 1.4986)
			(layers "F.Cu" "F.Mask" "F.Paste")
			(net "GND")
		)
		(pad "205" smd rect
			(at 2.050034 -12.325096 270)
			(size 0.519938 1.4986)
			(layers "F.Cu" "F.Mask" "F.Paste")
			(net "M_F_CPU1_SA_CB<7>")
		)
		(pad "206" smd rect
			(at 2.050034 -11.474958 270)
			(size 0.519938 1.4986)
			(layers "F.Cu" "F.Mask" "F.Paste")
			(net "GND")
		)
		(pad "207" smd rect
			(at 2.050034 -10.625074 270)
			(size 0.519938 1.4986)
			(layers "F.Cu" "F.Mask" "F.Paste")
			(net "RST_M_EF_CPU1_FPGA_N")
		)
		(pad "208" smd rect
			(at 2.050034 -9.774936 270)
			(size 0.519938 1.4986)
			(layers "F.Cu" "F.Mask" "F.Paste")
			(net "GND")
		)
		(pad "209" smd rect
			(at 2.050034 -8.925052 270)
			(size 0.519938 1.4986)
			(layers "F.Cu" "F.Mask" "F.Paste")
			(net "M_F_CPU1_SA_CS_N<1>")
		)
		(pad "210" smd rect
			(at 2.050034 -8.074914 270)
			(size 0.519938 1.4986)
			(layers "F.Cu" "F.Mask" "F.Paste")
			(net "GND")
		)
		(pad "211" smd rect
			(at 2.050034 -7.22503 270)
			(size 0.519938 1.4986)
			(layers "F.Cu" "F.Mask" "F.Paste")
			(net "M_F_CPU1_SA_CA<1>")
		)
		(pad "212" smd rect
			(at 2.050034 -6.374892 270)
			(size 0.519938 1.4986)
			(layers "F.Cu" "F.Mask" "F.Paste")
			(net "GND")
		)
		(pad "213" smd rect
			(at 2.050034 -5.525008 270)
			(size 0.519938 1.4986)
			(layers "F.Cu" "F.Mask" "F.Paste")
			(net "M_F_CPU1_SA_CA<3>")
		)
		(pad "214" smd rect
			(at 2.050034 -4.675124 270)
			(size 0.519938 1.4986)
			(layers "F.Cu" "F.Mask" "F.Paste")
			(net "GND")
		)
		(pad "215" smd rect
			(at 2.050034 -3.824986 270)
			(size 0.519938 1.4986)
			(layers "F.Cu" "F.Mask" "F.Paste")
			(net "M_F_CPU1_SA_CA<5>")
		)
		(pad "216" smd rect
			(at 2.050034 -2.975102 270)
			(size 0.519938 1.4986)
			(layers "F.Cu" "F.Mask" "F.Paste")
			(net "GND")
		)
		(pad "217" smd rect
			(at 2.050034 -2.124964 270)
			(size 0.519938 1.4986)
			(layers "F.Cu" "F.Mask" "F.Paste")
			(net "M_F_CPU1_CLK_DP<0>")
		)
		(pad "218" smd rect
			(at 2.050034 -1.27508 270)
			(size 0.519938 1.4986)
			(layers "F.Cu" "F.Mask" "F.Paste")
			(net "M_F_CPU1_CLK_DN<0>")
		)
		(pad "219" smd rect
			(at 2.050034 -0.424942 270)
			(size 0.519938 1.4986)
			(layers "F.Cu" "F.Mask" "F.Paste")
			(net "GND")
		)
		(pad "220" smd rect
			(at 2.050034 5.525008 270)
			(size 0.519938 1.4986)
			(layers "F.Cu" "F.Mask" "F.Paste")
			(net "TP_CHF_CPU1_DIMM1_FRU_4")
		)
		(pad "221" smd rect
			(at 2.050034 6.374892 270)
			(size 0.519938 1.4986)
			(layers "F.Cu" "F.Mask" "F.Paste")
			(net "M_F_CPU1_SB_CA<1>")
		)
		(pad "222" smd rect
			(at 2.050034 7.22503 270)
			(size 0.519938 1.4986)
			(layers "F.Cu" "F.Mask" "F.Paste")
			(net "GND")
		)
		(pad "223" smd rect
			(at 2.050034 8.074914 270)
			(size 0.519938 1.4986)
			(layers "F.Cu" "F.Mask" "F.Paste")
			(net "M_F_CPU1_SB_CA<3>")
		)
		(pad "224" smd rect
			(at 2.050034 8.925052 270)
			(size 0.519938 1.4986)
			(layers "F.Cu" "F.Mask" "F.Paste")
			(net "GND")
		)
		(pad "225" smd rect
			(at 2.050034 9.774936 270)
			(size 0.519938 1.4986)
			(layers "F.Cu" "F.Mask" "F.Paste")
			(net "M_F_CPU1_SB_CA<5>")
		)
		(pad "226" smd rect
			(at 2.050034 10.625074 270)
			(size 0.519938 1.4986)
			(layers "F.Cu" "F.Mask" "F.Paste")
			(net "GND")
		)
		(pad "227" smd rect
			(at 2.050034 11.474958 270)
			(size 0.519938 1.4986)
			(layers "F.Cu" "F.Mask" "F.Paste")
			(net "M_F_CPU1_SB_PAR")
		)
		(pad "228" smd rect
			(at 2.050034 12.325096 270)
			(size 0.519938 1.4986)
			(layers "F.Cu" "F.Mask" "F.Paste")
			(net "GND")
		)
	)
)
